(kicad_pcb
	(version 20241229)
	(generator "pcbnew")
	(generator_version "9.0")
	(general
		(thickness 1.711)
		(legacy_teardrops no)
	)
	(paper "A4")
	(title_block
		(title "Antmicro Baseboard for Jetson AGX Thor")
		(date "2026-02-18")
		(rev "1.1.0")
		(company "Antmicro Ltd")
		(comment 1 "www.antmicro.com")
		(comment 9 "footprints 1086-1089 of 1170")
	)
	(layers
		(0 "F.Cu" signal)
		(4 "In1.Cu" signal)
		(6 "In2.Cu" signal)
		(8 "In3.Cu" signal)
		(10 "In4.Cu" jumper)
		(12 "In5.Cu" signal)
		(14 "In6.Cu" signal)
		(16 "In7.Cu" signal)
		(18 "In8.Cu" signal)
		(2 "B.Cu" signal)
		(9 "F.Adhes" user "F.Adhesive")
		(11 "B.Adhes" user "B.Adhesive")
		(13 "F.Paste" user)
		(15 "B.Paste" user)
		(5 "F.SilkS" user "F.Silkscreen")
		(7 "B.SilkS" user "B.Silkscreen")
		(1 "F.Mask" user)
		(3 "B.Mask" user)
		(17 "Dwgs.User" user "User.Drawings")
		(19 "Cmts.User" user "User.Comments")
		(21 "Eco1.User" user "User.Eco1")
		(23 "Eco2.User" user "User.Eco2")
		(25 "Edge.Cuts" user)
		(27 "Margin" user)
		(31 "F.CrtYd" user "F.Courtyard")
		(29 "B.CrtYd" user "B.Courtyard")
		(35 "F.Fab" user)
		(33 "B.Fab" user)
	)
	(footprint "antmicro-footprints:Spacer_Drill3.7mm_H8mm_9774080151R"
		(locked yes)
		(layer "B.Cu")
		(at 222.430532 143.71 -90)
		(descr "Spacer M=3 h=8mm fi=5.1mm")
		(property "Reference" "H4"
			(at 0 3.2 90)
			(layer "B.SilkS")
			(effects
				(font
					(size 0.7 0.7)
					(thickness 0.15)
				)
				(justify left bottom mirror)
			)
		)
		(property "Value" "Spacer_Drill3.7mm_H8mm_9774080151R"
			(at 0 -4 90)
			(layer "B.Fab")
			(effects
				(font
					(size 0.7 0.7)
					(thickness 0.15)
				)
				(justify left bottom mirror)
			)
		)
		(property "Datasheet" "https://www.we-online.com/components/products/datasheet/9774080151R.pdf"
			(at 0 0 90)
			(layer "B.Fab")
			(hide yes)
			(effects
				(font
					(size 1.27 1.27)
					(thickness 0.15)
				)
				(justify mirror)
			)
		)
		(property "Description" "Spacer, SMT, Non Stop, Steel, Swage Round, 5.1 mm x 8 mm, M2.5 Thread, WA-SMSI Series"
			(at 0 0 90)
			(layer "B.Fab")
			(hide yes)
			(effects
				(font
					(size 1.27 1.27)
					(thickness 0.15)
				)
				(justify mirror)
			)
		)
		(property "Manufacturer" "Würth Elektronik"
			(at 0 0 270)
			(unlocked yes)
			(layer "B.Fab")
			(hide yes)
			(effects
				(font
					(size 1 1)
					(thickness 0.15)
				)
				(justify mirror)
			)
		)
		(property "MPN" "9774080151R"
			(at 0 0 270)
			(unlocked yes)
			(layer "B.Fab")
			(hide yes)
			(effects
				(font
					(size 1 1)
					(thickness 0.15)
				)
				(justify mirror)
			)
		)
		(property "Author" "Antmicro"
			(at 0 0 270)
			(unlocked yes)
			(layer "B.Fab")
			(hide yes)
			(effects
				(font
					(size 1 1)
					(thickness 0.15)
				)
				(justify mirror)
			)
		)
		(property "License" "Apache-2.0"
			(at 0 0 270)
			(unlocked yes)
			(layer "B.Fab")
			(hide yes)
			(effects
				(font
					(size 1 1)
					(thickness 0.15)
				)
				(justify mirror)
			)
		)
		(sheetname "/")
		(sheetfile "jetson-agx-thor-baseboard.kicad_sch")
		(solder_paste_margin_ratio -1)
		(attr smd)
		(fp_circle
			(center 0 0)
			(end 3.05 0)
			(stroke
				(width 0.05)
				(type solid)
			)
			(fill no)
			(layer "B.CrtYd")
		)
		(fp_circle
			(center 0 0)
			(end 2.6 0)
			(stroke
				(width 0.15)
				(type solid)
			)
			(fill no)
			(layer "B.Fab")
		)
		(fp_text user "${REFERENCE}"
			(at -9.6 -6.5 90)
			(layer "B.Fab")
			(effects
				(font
					(size 0.7 0.7)
					(thickness 0.15)
				)
				(justify left bottom mirror)
			)
		)
		(fp_text user "License: Apache-2.0"
			(at -9.6 -8.9 90)
			(layer "B.Fab")
			(effects
				(font
					(size 0.7 0.7)
					(thickness 0.15)
				)
				(justify left bottom mirror)
			)
		)
		(fp_text user "Author: Antmicro"
			(at -9.6 -7.7 90)
			(layer "B.Fab")
			(effects
				(font
					(size 0.7 0.7)
					(thickness 0.15)
				)
				(justify left bottom mirror)
			)
		)
		(pad "" smd custom
			(at -1.7 -1.7 180)
			(size 0.62 0.62)
			(layers "B.Paste")
			(thermal_bridge_angle 90)
			(options
				(clearance outline)
				(anchor circle)
			)
			(primitives
				(gr_arc
					(start 1.266786 0.24747)
					(mid 0.285453 -0.29439)
					(end -0.250195 -1.279127)
					(width 0.2)
				)
				(gr_arc
					(start 1.259603 0.339191)
					(mid 0.218448 -0.232561)
					(end -0.34334 -1.279127)
					(width 0.2)
				)
				(gr_arc
					(start 1.255279 0.431435)
					(mid 0.152481 -0.169693)
					(end -0.436309 -1.279127)
					(width 0.2)
				)
				(gr_arc
					(start 1.253811 0.524161)
					(mid 0.087542 -0.105784)
					(end -0.529126 -1.279127)
					(width 0.2)
				)
				(gr_arc
					(start 1.275473 0.621136)
					(mid 0.0309 -0.033527)
					(end -0.621807 -1.279127)
					(width 0.2)
				)
				(gr_arc
					(start 1.263664 0.711602)
					(mid -0.037759 0.026651)
					(end -0.71437 -1.279127)
					(width 0.2)
				)
				(gr_arc
					(start 1.253435 0.802342)
					(mid -0.105837 0.087395)
					(end -0.806826 -1.279127)
					(width 0.2)
				)
				(gr_arc
					(start 1.267475 0.897258)
					(mid -0.165236 0.156885)
					(end -0.899187 -1.279127)
					(width 0.2)
				)
				(gr_arc
					(start 1.270645 0.990112)
					(mid -0.228522 0.222449)
					(end -0.991463 -1.279127)
					(width 0.2)
				)
				(gr_arc
					(start 1.266278 1.081674)
					(mid -0.294507 0.285313)
					(end -1.083663 -1.279127)
					(width 0.2)
				)
				(gr_line
					(start 1.279127 0.250195)
					(end 1.279127 1.083663)
					(width 0.2)
				)
				(gr_line
					(start -0.250195 -1.279127)
					(end -1.083663 -1.279127)
					(width 0.2)
				)
			)
		)
		(pad "" smd custom
			(at -1.7 1.7 270)
			(size 0.62 0.62)
			(layers "B.Paste")
			(thermal_bridge_angle 90)
			(options
				(clearance outline)
				(anchor circle)
			)
			(primitives
				(gr_arc
					(start 1.266786 0.24747)
					(mid 0.285453 -0.29439)
					(end -0.250195 -1.279127)
					(width 0.2)
				)
				(gr_arc
					(start 1.259603 0.339191)
					(mid 0.218448 -0.232561)
					(end -0.34334 -1.279127)
					(width 0.2)
				)
				(gr_arc
					(start 1.255279 0.431435)
					(mid 0.152481 -0.169693)
					(end -0.436309 -1.279127)
					(width 0.2)
				)
				(gr_arc
					(start 1.253811 0.524161)
					(mid 0.087542 -0.105784)
					(end -0.529126 -1.279127)
					(width 0.2)
				)
				(gr_arc
					(start 1.275473 0.621136)
					(mid 0.0309 -0.033527)
					(end -0.621807 -1.279127)
					(width 0.2)
				)
				(gr_arc
					(start 1.263664 0.711602)
					(mid -0.037759 0.026651)
					(end -0.71437 -1.279127)
					(width 0.2)
				)
				(gr_arc
					(start 1.253435 0.802342)
					(mid -0.105837 0.087395)
					(end -0.806826 -1.279127)
					(width 0.2)
				)
				(gr_arc
					(start 1.267475 0.897258)
					(mid -0.165236 0.156885)
					(end -0.899187 -1.279127)
					(width 0.2)
				)
				(gr_arc
					(start 1.270645 0.990112)
					(mid -0.228522 0.222449)
					(end -0.991463 -1.279127)
					(width 0.2)
				)
				(gr_arc
					(start 1.266278 1.081674)
					(mid -0.294507 0.285313)
					(end -1.083663 -1.279127)
					(width 0.2)
				)
				(gr_line
					(start 1.279127 0.250195)
					(end 1.279127 1.083663)
					(width 0.2)
				)
				(gr_line
					(start -0.250195 -1.279127)
					(end -1.083663 -1.279127)
					(width 0.2)
				)
			)
		)
		(pad "" smd custom
			(at 1.7 -1.7 90)
			(size 0.62 0.62)
			(layers "B.Paste")
			(thermal_bridge_angle 90)
			(options
				(clearance outline)
				(anchor circle)
			)
			(primitives
				(gr_arc
					(start 1.266786 0.24747)
					(mid 0.285453 -0.29439)
					(end -0.250195 -1.279127)
					(width 0.2)
				)
				(gr_arc
					(start 1.259603 0.339191)
					(mid 0.218448 -0.232561)
					(end -0.34334 -1.279127)
					(width 0.2)
				)
				(gr_arc
					(start 1.255279 0.431435)
					(mid 0.152481 -0.169693)
					(end -0.436309 -1.279127)
					(width 0.2)
				)
				(gr_arc
					(start 1.253811 0.524161)
					(mid 0.087542 -0.105784)
					(end -0.529126 -1.279127)
					(width 0.2)
				)
				(gr_arc
					(start 1.275473 0.621136)
					(mid 0.0309 -0.033527)
					(end -0.621807 -1.279127)
					(width 0.2)
				)
				(gr_arc
					(start 1.263664 0.711602)
					(mid -0.037759 0.026651)
					(end -0.71437 -1.279127)
					(width 0.2)
				)
				(gr_arc
					(start 1.253435 0.802342)
					(mid -0.105837 0.087395)
					(end -0.806826 -1.279127)
					(width 0.2)
				)
				(gr_arc
					(start 1.267475 0.897258)
					(mid -0.165236 0.156885)
					(end -0.899187 -1.279127)
					(width 0.2)
				)
				(gr_arc
					(start 1.270645 0.990112)
					(mid -0.228522 0.222449)
					(end -0.991463 -1.279127)
					(width 0.2)
				)
				(gr_arc
					(start 1.266278 1.081674)
					(mid -0.294507 0.285313)
					(end -1.083663 -1.279127)
					(width 0.2)
				)
				(gr_line
					(start 1.279127 0.250195)
					(end 1.279127 1.083663)
					(width 0.2)
				)
				(gr_line
					(start -0.250195 -1.279127)
					(end -1.083663 -1.279127)
					(width 0.2)
				)
			)
		)
		(pad "" smd custom
			(at 1.7 1.7)
			(size 0.62 0.62)
			(layers "B.Paste")
			(thermal_bridge_angle 90)
			(options
				(clearance outline)
				(anchor circle)
			)
			(primitives
				(gr_arc
					(start 1.266786 0.24747)
					(mid 0.285453 -0.29439)
					(end -0.250195 -1.279127)
					(width 0.2)
				)
				(gr_arc
					(start 1.259603 0.339191)
					(mid 0.218448 -0.232561)
					(end -0.34334 -1.279127)
					(width 0.2)
				)
				(gr_arc
					(start 1.255279 0.431435)
					(mid 0.152481 -0.169693)
					(end -0.436309 -1.279127)
					(width 0.2)
				)
				(gr_arc
					(start 1.253811 0.524161)
					(mid 0.087542 -0.105784)
					(end -0.529126 -1.279127)
					(width 0.2)
				)
				(gr_arc
					(start 1.275473 0.621136)
					(mid 0.0309 -0.033527)
					(end -0.621807 -1.279127)
					(width 0.2)
				)
				(gr_arc
					(start 1.263664 0.711602)
					(mid -0.037759 0.026651)
					(end -0.71437 -1.279127)
					(width 0.2)
				)
				(gr_arc
					(start 1.253435 0.802342)
					(mid -0.105837 0.087395)
					(end -0.806826 -1.279127)
					(width 0.2)
				)
				(gr_arc
					(start 1.267475 0.897258)
					(mid -0.165236 0.156885)
					(end -0.899187 -1.279127)
					(width 0.2)
				)
				(gr_arc
					(start 1.270645 0.990112)
					(mid -0.228522 0.222449)
					(end -0.991463 -1.279127)
					(width 0.2)
				)
				(gr_arc
					(start 1.266278 1.081674)
					(mid -0.294507 0.285313)
					(end -1.083663 -1.279127)
					(width 0.2)
				)
				(gr_line
					(start 1.279127 0.250195)
					(end 1.279127 1.083663)
					(width 0.2)
				)
				(gr_line
					(start -0.250195 -1.279127)
					(end -1.083663 -1.279127)
					(width 0.2)
				)
			)
		)
		(pad "1" thru_hole circle
			(at 0 0 270)
			(size 6 6)
			(drill 3.7)
			(layers "*.Cu" "*.Mask")
			(remove_unused_layers no)
			(net 1 "GND")
			(pintype "passive")
		)
	)
	(footprint "antmicro-footprints:TP_SMD_0.75mm"
		(layer "B.Cu")
		(at 206.066532 147.62 -90)
		(property "Reference" "TP30"
			(at 0.48 0.740532 0)
			(layer "B.SilkS")
			(effects
				(font
					(size 0.7 0.7)
					(thickness 0.15)
				)
				(justify left bottom mirror)
			)
		)
		(property "Value" "TP_0.75mm_SMD"
			(at 0 -1.2 90)
			(layer "B.Fab")
			(effects
				(font
					(size 0.7 0.7)
					(thickness 0.15)
				)
				(justify left bottom mirror)
			)
		)
		(property "Description" "SMT test point"
			(at 0 0 90)
			(layer "B.Fab")
			(hide yes)
			(effects
				(font
					(size 1.27 1.27)
					(thickness 0.15)
				)
				(justify mirror)
			)
		)
		(property "MPN" ""
			(at 0 0 90)
			(unlocked yes)
			(layer "B.Fab")
			(hide yes)
			(effects
				(font
					(size 1 1)
					(thickness 0.15)
				)
				(justify mirror)
			)
		)
		(property "Manufacturer" ""
			(at 0 0 90)
			(unlocked yes)
			(layer "B.Fab")
			(hide yes)
			(effects
				(font
					(size 1 1)
					(thickness 0.15)
				)
				(justify mirror)
			)
		)
		(property "Author" "Antmicro"
			(at 0 0 90)
			(unlocked yes)
			(layer "B.Fab")
			(hide yes)
			(effects
				(font
					(size 1 1)
					(thickness 0.15)
				)
				(justify mirror)
			)
		)
		(property "License" "Apache-2.0"
			(at 0 0 90)
			(unlocked yes)
			(layer "B.Fab")
			(hide yes)
			(effects
				(font
					(size 1 1)
					(thickness 0.15)
				)
				(justify mirror)
			)
		)
		(sheetname "/SFP/")
		(sheetfile "sfp.kicad_sch")
		(attr exclude_from_pos_files exclude_from_bom)
		(fp_circle
			(center 0 0)
			(end 0.475 0)
			(stroke
				(width 0.05)
				(type default)
			)
			(fill no)
			(layer "B.CrtYd")
		)
		(fp_text user "Author: Antmicro"
			(at -0.4 -3.901 90)
			(layer "B.Fab")
			(effects
				(font
					(size 0.7 0.7)
					(thickness 0.15)
				)
				(justify left bottom mirror)
			)
		)
		(fp_text user "${REFERENCE}"
			(at -0.4 -2.7 90)
			(layer "B.Fab")
			(effects
				(font
					(size 0.7 0.7)
					(thickness 0.15)
				)
				(justify left bottom mirror)
			)
		)
		(fp_text user "License: Apache-2.0"
			(at -0.4 -5.101 90)
			(layer "B.Fab")
			(effects
				(font
					(size 0.7 0.7)
					(thickness 0.15)
				)
				(justify left bottom mirror)
			)
		)
		(pad "1" smd circle
			(at 0 0 270)
			(size 0.75 0.75)
			(layers "B.Cu" "B.Mask")
			(net 1371 "Net-(J12-TX_{FAULT})")
			(pinfunction "1")
			(pintype "passive")
		)
	)
	(footprint "antmicro-footprints:Fiducial_1mm_Mask3mm"
		(layer "B.Cu")
		(at 235.3 149.12 180)
		(descr "Circular Fiducial, 1.5mm bare copper, 3mm soldermask opening")
		(tags "fiducial")
		(property "Reference" "FD6"
			(at -0.95 1.66 0)
			(layer "B.SilkS")
			(effects
				(font
					(size 0.7 0.7)
					(thickness 0.15)
				)
				(justify left bottom mirror)
			)
		)
		(property "Value" "Fiducial_1mm_Mask3mm"
			(at 0 -2.603 0)
			(layer "B.Fab")
			(effects
				(font
					(size 0.7 0.7)
					(thickness 0.15)
				)
				(justify left bottom mirror)
			)
		)
		(property "Description" "Fiducial mask"
			(at 0 0 0)
			(layer "B.Fab")
			(hide yes)
			(effects
				(font
					(size 1.27 1.27)
					(thickness 0.15)
				)
				(justify mirror)
			)
		)
		(property "Author" "Antmicro"
			(at 0 0 0)
			(unlocked yes)
			(layer "B.Fab")
			(hide yes)
			(effects
				(font
					(size 1 1)
					(thickness 0.15)
				)
				(justify mirror)
			)
		)
		(property "License" "Apache-2.0"
			(at 0 0 0)
			(unlocked yes)
			(layer "B.Fab")
			(hide yes)
			(effects
				(font
					(size 1 1)
					(thickness 0.15)
				)
				(justify mirror)
			)
		)
		(sheetname "/")
		(sheetfile "jetson-agx-thor-baseboard.kicad_sch")
		(attr exclude_from_pos_files exclude_from_bom)
		(fp_circle
			(center 0 0)
			(end 1.5 0)
			(stroke
				(width 0.05)
				(type solid)
			)
			(fill no)
			(layer "B.CrtYd")
		)
		(fp_circle
			(center 0 0)
			(end 1.5 0)
			(stroke
				(width 0.15)
				(type solid)
			)
			(fill no)
			(layer "B.Fab")
		)
		(fp_text user "License: Apache-2.0"
			(at -1.25 -7.003 0)
			(layer "B.Fab")
			(effects
				(font
					(size 0.7 0.7)
					(thickness 0.15)
				)
				(justify left bottom mirror)
			)
		)
		(fp_text user "Author: Antmicro"
			(at -1.25 -5.803 0)
			(layer "B.Fab")
			(effects
				(font
					(size 0.7 0.7)
					(thickness 0.15)
				)
				(justify left bottom mirror)
			)
		)
		(fp_text user "${REFERENCE}"
			(at -1.25 -4.603 0)
			(layer "B.Fab")
			(effects
				(font
					(size 0.7 0.7)
					(thickness 0.15)
				)
				(justify left bottom mirror)
			)
		)
		(pad "" smd circle
			(at 0 0 180)
			(size 1 1)
			(layers "B.Cu" "B.Mask")
			(solder_mask_margin 1)
			(clearance 1)
		)
	)
	(footprint "antmicro-footprints:R_0402_1005Metric"
		(layer "B.Cu")
		(at 193.7 84.1)
		(descr "Resistor SMD 0402")
		(tags "resistor SMD 0402")
		(property "Reference" "R98"
			(at -1.225 -1.454 0)
			(layer "B.SilkS")
			(effects
				(font
					(size 0.7 0.7)
					(thickness 0.15)
				)
				(justify right top mirror)
			)
		)
		(property "Value" "R_10k_0402"
			(at -1.011843 -1.772046 0)
			(layer "B.Fab")
			(effects
				(font
					(size 0.7 0.7)
					(thickness 0.15)
				)
				(justify right top mirror)
			)
		)
		(property "Datasheet" "https://www.bourns.com/docs/product-datasheets/cr.pdf"
			(at 0 0 0)
			(layer "B.Fab")
			(hide yes)
			(effects
				(font
					(size 1.27 1.27)
					(thickness 0.15)
				)
				(justify mirror)
			)
		)
		(property "Description" "SMD Chip Resistor, 10 kohm, ± 1%, 62.5 mW, 0402 [1005 Metric], Thick Film, General Purpose"
			(at 0 0 0)
			(layer "B.Fab")
			(hide yes)
			(effects
				(font
					(size 1.27 1.27)
					(thickness 0.15)
				)
				(justify mirror)
			)
		)
		(property "MPN" "CR0402-FX-1002GLF"
			(at 0 0 180)
			(unlocked yes)
			(layer "B.Fab")
			(hide yes)
			(effects
				(font
					(size 1 1)
					(thickness 0.15)
				)
				(justify mirror)
			)
		)
		(property "Manufacturer" "Bourns"
			(at 0 0 180)
			(unlocked yes)
			(layer "B.Fab")
			(hide yes)
			(effects
				(font
					(size 1 1)
					(thickness 0.15)
				)
				(justify mirror)
			)
		)
		(property "License" "Apache-2.0"
			(at 0 0 180)
			(unlocked yes)
			(layer "B.Fab")
			(hide yes)
			(effects
				(font
					(size 1 1)
					(thickness 0.15)
				)
				(justify mirror)
			)
		)
		(property "Author" "Antmicro"
			(at 0 0 180)
			(unlocked yes)
			(layer "B.Fab")
			(hide yes)
			(effects
				(font
					(size 1 1)
					(thickness 0.15)
				)
				(justify mirror)
			)
		)
		(property "Val" "10k"
			(at 0 0 180)
			(unlocked yes)
			(layer "B.Fab")
			(hide yes)
			(effects
				(font
					(size 1 1)
					(thickness 0.15)
				)
				(justify mirror)
			)
		)
		(property "Tolerance" "1%"
			(at 0 0 180)
			(unlocked yes)
			(layer "B.Fab")
			(hide yes)
			(effects
				(font
					(size 1 1)
					(thickness 0.15)
				)
				(justify mirror)
			)
		)
		(sheetname "/USB Debug, PD/")
		(sheetfile "usb_debug_pd.kicad_sch")
		(attr smd)
		(fp_poly
			(pts
				(xy -0.925 0.47) (xy -0.925 -0.47) (xy 0.925 -0.47) (xy 0.925 0.47)
			)
			(stroke
				(width 0.05)
				(type default)
			)
			(fill no)
			(layer "B.CrtYd")
		)
		(fp_poly
			(pts
				(xy -0.5 0.25) (xy -0.5 -0.25) (xy 0.5 -0.25) (xy 0.5 0.25)
			)
			(stroke
				(width 0.15)
				(type solid)
			)
			(fill no)
			(layer "B.Fab")
		)
		(fp_text user "Author: Antmicro"
			(at -0.95 -4.169 0)
			(layer "B.Fab")
			(effects
				(font
					(size 0.7 0.7)
					(thickness 0.15)
				)
				(justify right top mirror)
			)
		)
		(fp_text user "${REFERENCE}"
			(at -0.95 -3.168 0)
			(layer "B.Fab")
			(effects
				(font
					(size 0.7 0.7)
					(thickness 0.15)
				)
				(justify right top mirror)
			)
		)
		(fp_text user "License: Apache-2.0"
			(at -0.949999 -5.169 0)
			(layer "B.Fab")
			(effects
				(font
					(size 0.7 0.7)
					(thickness 0.15)
				)
				(justify right top mirror)
			)
		)
		(pad "1" smd roundrect
			(at -0.48 0)
			(size 0.59 0.64)
			(layers "B.Cu" "B.Mask" "B.Paste")
			(roundrect_rratio 0.25)
			(net 936 "/USB Debug, PD/PDC_MISO")
			(pintype "passive")
		)
		(pad "2" smd roundrect
			(at 0.48 0)
			(size 0.59 0.64)
			(layers "B.Cu" "B.Mask" "B.Paste")
			(roundrect_rratio 0.25)
			(net 271 "FLASH_PWR")
			(pintype "passive")
		)
	)
)
